# TIMECARD (Time Appliance Project (Time Card)) — schematic netlist excerpt (pin names and nets, part order shuffled) for the footprints in the layout excerpt that follows; sources: Cadence DE-HDL packaged netlist, KiCad conversion of R4006-B0001-02_R01.brd

R154  RESISTOR  4.7KOHM 1%  pkg SMC_0402R_H016  page 16 : \1\ = SG ; \2\ = UNNAMED_5_PCA9546APWTSSOP16_I_2
C297  CAPACITOR  10UF 25V 20%  pkg SMC_0805R_H057  page 27 : \1\ = XP12R0V_IN ; \2\ = SG

(kicad_pcb
	(version 20260206)
	(generator "pcbnew")
	(generator_version "10.0")
	(general
		(thickness 1.6)
		(legacy_teardrops no)
	)
	(paper "A4")
	(title_block
		(title "timecard-production-celestica-r4006 — R4006-B0001-02_R01.brd")
		(comment 1 "Time Appliance Project (Time Card) / footprints 1108-1109 of 1113")
	)
	(layers
		(0 "F.Cu" signal "TOP")
		(4 "In1.Cu" signal "L02_GND1")
		(6 "In2.Cu" signal "L03_SIG1")
		(8 "In3.Cu" signal "L04_GND2")
		(10 "In4.Cu" signal "L05_VCC1")
		(12 "In5.Cu" signal "L06_VCC2")
		(14 "In6.Cu" signal "L07_GND3")
		(16 "In7.Cu" signal "L08_SIG2")
		(18 "In8.Cu" signal "L09_GND4")
		(2 "B.Cu" signal "BOTTOM")
		(9 "F.Adhes" user "F.Adhesive")
		(11 "B.Adhes" user "B.Adhesive")
		(13 "F.Paste" user "Package Geometry/Pastemask Top")
		(15 "B.Paste" user "Package Geometry/Pastemask Bottom")
		(5 "F.SilkS" user "Ref Des/Silkscreen Top")
		(7 "B.SilkS" user "Ref Des/Silkscreen Bottom")
		(1 "F.Mask" user "Board Geometry/Soldermask Top")
		(3 "B.Mask" user "Board Geometry/Soldermask Bottom")
		(17 "Dwgs.User" user "User.Drawings")
		(19 "Cmts.User" user "User.Comments")
		(21 "Eco1.User" user "User.Eco1")
		(23 "Eco2.User" user "User.Eco2")
		(25 "Edge.Cuts" user "Board Geometry/Outline")
		(27 "Margin" user)
		(31 "F.CrtYd" user "Package Geometry/Place Bound Top")
		(29 "B.CrtYd" user "Package Geometry/Place Bound Bottom")
		(35 "F.Fab" user "Ref Des/Assembly Top")
		(33 "B.Fab" user "Ref Des/Assembly Bottom")
	)
	(footprint ""
		(layer "B.Cu")
		(at 77.3938 -83.947)
		(property "Reference" "R154"
			(at -1.1938 -2.37363 0)
			(unlocked yes)
			(layer "B.SilkS")
			(effects
				(font
					(size 0.7874 0.5842)
					(thickness 0.1524)
				)
				(justify mirror)
			)
		)
		(property "Value" "VAL*"
			(at -0.02032 2.13233 0)
			(unlocked yes)
			(layer "B.Fab")
			(hide yes)
			(effects
				(font
					(size 0.7874 0.5842)
					(thickness 0.1524)
				)
				(justify mirror)
			)
		)
		(property "Tolerance" "TOL*"
			(at -0.044704 3.05435 0)
			(unlocked yes)
			(layer "Cmts.User")
			(hide yes)
			(effects
				(font
					(size 0.7874 0.5842)
					(thickness 0.1524)
				)
				(justify mirror)
			)
		)
		(property "User Part Number" "PARTNUM*"
			(at -0.02032 4.024884 0)
			(unlocked yes)
			(layer "Cmts.User")
			(hide yes)
			(effects
				(font
					(size 0.7874 0.5842)
					(thickness 0.1524)
				)
				(justify mirror)
			)
		)
		(property "Device Type" "RESISTOR-G155-14701-01,4.7KOHMA"
			(at -0.008382 1.210564 0)
			(unlocked yes)
			(layer "B.Fab")
			(hide yes)
			(effects
				(font
					(size 0.7874 0.5842)
					(thickness 0.1524)
				)
				(justify mirror)
			)
		)
		(duplicate_pad_numbers_are_jumpers no)
		(fp_line
			(start -1.143 -0.5588)
			(end 1.143 -0.5588)
			(stroke
				(width 0.1)
				(type default)
			)
			(layer "B.SilkS")
		)
		(fp_line
			(start -1.143 0.5588)
			(end -1.143 -0.5588)
			(stroke
				(width 0.1)
				(type default)
			)
			(layer "B.SilkS")
		)
		(fp_line
			(start 1.143 -0.5588)
			(end 1.143 0.5588)
			(stroke
				(width 0.1)
				(type default)
			)
			(layer "B.SilkS")
		)
		(fp_line
			(start 1.143 0.5588)
			(end -1.143 0.5588)
			(stroke
				(width 0.1)
				(type default)
			)
			(layer "B.SilkS")
		)
		(fp_rect
			(start 1.143 -0.5588)
			(end -1.143 0.5588)
			(stroke
				(width 0)
				(type default)
			)
			(fill no)
			(layer "B.CrtYd")
		)
		(fp_line
			(start -0.508 -0.3048)
			(end 0.508 -0.3048)
			(stroke
				(width 0.1)
				(type default)
			)
			(layer "B.Fab")
		)
		(fp_line
			(start -0.508 0.3048)
			(end -0.508 -0.3048)
			(stroke
				(width 0.1)
				(type default)
			)
			(layer "B.Fab")
		)
		(fp_line
			(start 0.508 -0.3048)
			(end 0.508 0.3048)
			(stroke
				(width 0.1)
				(type default)
			)
			(layer "B.Fab")
		)
		(fp_line
			(start 0.508 0.3048)
			(end -0.508 0.3048)
			(stroke
				(width 0.1)
				(type default)
			)
			(layer "B.Fab")
		)
		(pad "1" smd rect
			(at 0.5334 0 180)
			(size 0.7112 0.6096)
			(layers "B.Cu" "B.Mask" "B.Paste")
			(net "SG")
		)
		(pad "2" smd rect
			(at -0.5334 0 180)
			(size 0.7112 0.6096)
			(layers "B.Cu" "B.Mask" "B.Paste")
			(net "UNNAMED_5_PCA9546APWTSSOP16_I_2")
		)
		(zone
			(layer "B.Cu")
			(hatch none 0.5)
			(connect_pads
				(clearance 0)
			)
			(min_thickness 0.25)
			(keepout
				(tracks allowed)
				(vias not_allowed)
				(pads allowed)
				(copperpour not_allowed)
				(footprints allowed)
			)
			(placement
				(enabled no)
				(sheetname "")
			)
			(fill
				(thermal_gap 0.5)
				(thermal_bridge_width 0.5)
				(island_removal_mode 0)
			)
			(polygon
				(pts
					(xy 77.47 -84.2518) (xy 77.3176 -84.2518) (xy 77.3176 -83.6422) (xy 77.47 -83.6422)
				)
			)
		)
	)
	(footprint ""
		(layer "B.Cu")
		(at 139.6492 -85.4456)
		(property "Reference" "C297"
			(at 0.4318 -5.82803 0)
			(unlocked yes)
			(layer "B.SilkS")
			(effects
				(font
					(size 0.7874 0.5842)
					(thickness 0.1524)
				)
				(justify mirror)
			)
		)
		(property "Value" "VAL*"
			(at -0.0762 3.134106 0)
			(unlocked yes)
			(layer "B.Fab")
			(hide yes)
			(effects
				(font
					(size 0.7874 0.5842)
					(thickness 0.1524)
				)
				(justify mirror)
			)
		)
		(property "Device Type" "CAPACITOR-G107-0F106-EM,10UF,2A"
			(at -0.0508 2.194306 0)
			(unlocked yes)
			(layer "B.Fab")
			(hide yes)
			(effects
				(font
					(size 0.7874 0.5842)
					(thickness 0.1524)
				)
				(justify mirror)
			)
		)
		(property "User Part Number" "PARTNUM*"
			(at -0.1016 5.013706 0)
			(unlocked yes)
			(layer "Cmts.User")
			(hide yes)
			(effects
				(font
					(size 0.7874 0.5842)
					(thickness 0.1524)
				)
				(justify mirror)
			)
		)
		(property "Tolerance" "TOL*"
			(at -0.0762 4.048506 0)
			(unlocked yes)
			(layer "Cmts.User")
			(hide yes)
			(effects
				(font
					(size 0.7874 0.5842)
					(thickness 0.1524)
				)
				(justify mirror)
			)
		)
		(duplicate_pad_numbers_are_jumpers no)
		(fp_line
			(start -1.5748 -0.9398)
			(end 1.5748 -0.9398)
			(stroke
				(width 0.1)
				(type default)
			)
			(layer "B.SilkS")
		)
		(fp_line
			(start -1.5748 0.9398)
			(end -1.5748 -0.9398)
			(stroke
				(width 0.1)
				(type default)
			)
			(layer "B.SilkS")
		)
		(fp_line
			(start 1.5748 -0.9398)
			(end 1.5748 0.9398)
			(stroke
				(width 0.1)
				(type default)
			)
			(layer "B.SilkS")
		)
		(fp_line
			(start 1.5748 0.9398)
			(end -1.5748 0.9398)
			(stroke
				(width 0.1)
				(type default)
			)
			(layer "B.SilkS")
		)
		(fp_rect
			(start 1.5748 -0.9398)
			(end -1.5748 0.9398)
			(stroke
				(width 0)
				(type default)
			)
			(fill no)
			(layer "B.CrtYd")
		)
		(fp_line
			(start -1.016 -0.635)
			(end 1.016 -0.635)
			(stroke
				(width 0.1)
				(type default)
			)
			(layer "B.Fab")
		)
		(fp_line
			(start -1.016 0.635)
			(end -1.016 -0.635)
			(stroke
				(width 0.1)
				(type default)
			)
			(layer "B.Fab")
		)
		(fp_line
			(start 1.016 -0.635)
			(end 1.016 0.635)
			(stroke
				(width 0.1)
				(type default)
			)
			(layer "B.Fab")
		)
		(fp_line
			(start 1.016 0.635)
			(end -1.016 0.635)
			(stroke
				(width 0.1)
				(type default)
			)
			(layer "B.Fab")
		)
		(pad "1" smd rect
			(at 0.8382 0 180)
			(size 0.9652 1.3716)
			(layers "B.Cu" "B.Mask" "B.Paste")
			(net "XP12R0V_IN")
		)
		(pad "2" smd rect
			(at -0.8382 0 180)
			(size 0.9652 1.3716)
			(layers "B.Cu" "B.Mask" "B.Paste")
			(net "SG")
		)
		(zone
			(layer "B.Cu")
			(hatch none 0.5)
			(connect_pads
				(clearance 0)
			)
			(min_thickness 0.25)
			(keepout
				(tracks not_allowed)
				(vias allowed)
				(pads allowed)
				(copperpour not_allowed)
				(footprints allowed)
			)
			(placement
				(enabled no)
				(sheetname "")
			)
			(fill
				(thermal_gap 0.5)
				(thermal_bridge_width 0.5)
				(island_removal_mode 0)
			)
			(polygon
				(pts
					(xy 139.8778 -86.0806) (xy 139.4206 -86.0806) (xy 139.4206 -84.8106) (xy 139.8778 -84.8106)
				)
			)
		)
		(zone
			(layer "B.Cu")
			(hatch none 0.5)
			(connect_pads
				(clearance 0)
			)
			(min_thickness 0.25)
			(keepout
				(tracks allowed)
				(vias not_allowed)
				(pads allowed)
				(copperpour not_allowed)
				(footprints allowed)
			)
			(placement
				(enabled no)
				(sheetname "")
			)
			(fill
				(thermal_gap 0.5)
				(thermal_bridge_width 0.5)
				(island_removal_mode 0)
			)
			(polygon
				(pts
					(xy 139.8778 -86.0806) (xy 139.4206 -86.0806) (xy 139.4206 -84.8106) (xy 139.8778 -84.8106)
				)
			)
		)
	)
)
